(kicad_pcb
	(version 20260206)
	(generator "pcbnew")
	(generator_version "10.0")
	(general
		(thickness 1.6)
		(legacy_teardrops no)
	)
	(paper "A4")
	(title_block
		(title "01162023_DA0F0TEBIF0_F0T_Expander_BD_F_brd_V02_OCP.brd")
		(comment 1 "Grand Teton / footprints 8103-8109 of 9728")
	)
	(layers
		(0 "F.Cu" signal "TOP")
		(4 "In1.Cu" signal "GND")
		(6 "In2.Cu" signal "VCC")
		(8 "In3.Cu" signal "VCC1")
		(10 "In4.Cu" signal "GND1")
		(12 "In5.Cu" signal "IN1")
		(14 "In6.Cu" signal "GND2")
		(16 "In7.Cu" signal "IN2")
		(18 "In8.Cu" signal "GND3")
		(20 "In9.Cu" signal "IN3")
		(22 "In10.Cu" signal "GND4")
		(24 "In11.Cu" signal "IN4")
		(26 "In12.Cu" signal "GND5")
		(28 "In13.Cu" signal "IN5")
		(30 "In14.Cu" signal "GND6")
		(32 "In15.Cu" signal "IN6")
		(34 "In16.Cu" signal "GND7")
		(2 "B.Cu" signal "BOTTOM")
		(9 "F.Adhes" user "F.Adhesive")
		(11 "B.Adhes" user "B.Adhesive")
		(13 "F.Paste" user "Package Geometry/Pastemask Top")
		(15 "B.Paste" user "Package Geometry/Pastemask Bottom")
		(5 "F.SilkS" user "Ref Des/Silkscreen Top")
		(7 "B.SilkS" user "Ref Des/Silkscreen Bottom")
		(1 "F.Mask" user "Board Geometry/Soldermask Top")
		(3 "B.Mask" user "Board Geometry/Soldermask Bottom")
		(17 "Dwgs.User" user "User.Drawings")
		(19 "Cmts.User" user "User.Comments")
		(21 "Eco1.User" user "User.Eco1")
		(23 "Eco2.User" user "User.Eco2")
		(25 "Edge.Cuts" user "Board Geometry/Outline")
		(27 "Margin" user)
		(31 "F.CrtYd" user "Package Geometry/Place Bound Top")
		(29 "B.CrtYd" user "Package Geometry/Place Bound Bottom")
		(35 "F.Fab" user "Ref Des/Assembly Top")
		(33 "B.Fab" user "Ref Des/Assembly Bottom")
	)
	(footprint ""
		(layer "B.Cu")
		(at 346.093796 -217.187018 90)
		(property "Reference" "C2049"
			(at 0 0 90)
			(layer "B.SilkS")
			(hide yes)
			(effects
				(font
					(size 1.27 1.27)
				)
				(justify mirror)
			)
		)
		(property "Value" ""
			(at 0 0 90)
			(layer "B.Fab")
			(effects
				(font
					(size 1.27 1.27)
				)
				(justify mirror)
			)
		)
		(duplicate_pad_numbers_are_jumpers no)
		(fp_line
			(start 0.69215 -0.2921)
			(end -0.69215 -0.2921)
			(stroke
				(width 0.1524)
				(type default)
			)
			(layer "B.SilkS")
		)
		(fp_line
			(start -0.69215 -0.2921)
			(end -0.69215 0.2921)
			(stroke
				(width 0.1524)
				(type default)
			)
			(layer "B.SilkS")
		)
		(fp_line
			(start 0.69215 0.2921)
			(end 0.69215 -0.2921)
			(stroke
				(width 0.1524)
				(type default)
			)
			(layer "B.SilkS")
		)
		(fp_line
			(start -0.69215 0.2921)
			(end 0.69215 0.2921)
			(stroke
				(width 0.1524)
				(type default)
			)
			(layer "B.SilkS")
		)
		(fp_line
			(start 0.51435 -0.2794)
			(end -0.51435 -0.2794)
			(stroke
				(width 0.1)
				(type default)
			)
			(layer "B.Fab")
		)
		(fp_line
			(start -0.51435 -0.2794)
			(end -0.51435 0.2794)
			(stroke
				(width 0.1)
				(type default)
			)
			(layer "B.Fab")
		)
		(fp_line
			(start 0.51435 0.2794)
			(end 0.51435 -0.2794)
			(stroke
				(width 0.1)
				(type default)
			)
			(layer "B.Fab")
		)
		(fp_line
			(start -0.51435 0.2794)
			(end 0.51435 0.2794)
			(stroke
				(width 0.1)
				(type default)
			)
			(layer "B.Fab")
		)
		(pad "1" smd circle
			(at 0.40005 0 270)
			(size 0 0)
			(layers "B.Cu" "B.Mask" "B.Paste")
			(net "P3V3_FPGA_VCCIO1")
		)
		(pad "2" smd circle
			(at -0.40005 0 270)
			(size 0 0)
			(layers "B.Cu" "B.Mask" "B.Paste")
			(net "GND")
		)
		(zone
			(layer "B.Cu")
			(hatch none 0.5)
			(connect_pads
				(clearance 0)
			)
			(min_thickness 0.25)
			(keepout
				(tracks not_allowed)
				(vias allowed)
				(pads allowed)
				(copperpour not_allowed)
				(footprints allowed)
			)
			(placement
				(enabled no)
				(sheetname "")
			)
			(fill
				(thermal_gap 0.5)
				(thermal_bridge_width 0.5)
				(island_removal_mode 0)
			)
			(polygon
				(pts
					(xy 346.181426 -217.377518) (xy 346.239592 -217.286078) (xy 346.239592 -217.086688) (xy 346.181426 -216.996518)
					(xy 346.006166 -216.996518) (xy 345.947746 -217.086688) (xy 345.947746 -217.286078) (xy 346.005912 -217.377518)
				)
			)
		)
	)
	(footprint ""
		(layer "B.Cu")
		(at 452.08444 -288.320988)
		(property "Reference" "PC272"
			(at 0 0 0)
			(layer "B.SilkS")
			(hide yes)
			(effects
				(font
					(size 1.27 1.27)
				)
				(justify mirror)
			)
		)
		(property "Value" ""
			(at 0 0 0)
			(layer "B.Fab")
			(effects
				(font
					(size 1.27 1.27)
				)
				(justify mirror)
			)
		)
		(duplicate_pad_numbers_are_jumpers no)
		(fp_line
			(start -1.524 -0.762)
			(end -1.524 0.762)
			(stroke
				(width 0.1524)
				(type default)
			)
			(layer "B.SilkS")
		)
		(fp_line
			(start -1.524 0.762)
			(end 1.524 0.762)
			(stroke
				(width 0.1524)
				(type default)
			)
			(layer "B.SilkS")
		)
		(fp_line
			(start 1.524 -0.762)
			(end -1.524 -0.762)
			(stroke
				(width 0.1524)
				(type default)
			)
			(layer "B.SilkS")
		)
		(fp_line
			(start 1.524 0.762)
			(end 1.524 -0.762)
			(stroke
				(width 0.1524)
				(type default)
			)
			(layer "B.SilkS")
		)
		(fp_line
			(start -1.1049 -0.724916)
			(end 1.1049 -0.724916)
			(stroke
				(width 0.1)
				(type default)
			)
			(layer "B.Fab")
		)
		(fp_line
			(start -1.1049 0.724916)
			(end -1.1049 -0.724916)
			(stroke
				(width 0.1)
				(type default)
			)
			(layer "B.Fab")
		)
		(fp_line
			(start 1.1049 -0.724916)
			(end 1.1049 0.724916)
			(stroke
				(width 0.1)
				(type default)
			)
			(layer "B.Fab")
		)
		(fp_line
			(start 1.1049 0.724916)
			(end -1.1049 0.724916)
			(stroke
				(width 0.1)
				(type default)
			)
			(layer "B.Fab")
		)
		(pad "1" smd rect
			(at 0.889 0)
			(size 1.016 1.27)
			(layers "B.Cu" "B.Mask" "B.Paste")
			(net "P1V25_PEX3_R")
		)
		(pad "2" smd rect
			(at -0.889 0)
			(size 1.016 1.27)
			(layers "B.Cu" "B.Mask" "B.Paste")
			(net "GND")
		)
	)
	(footprint ""
		(layer "B.Cu")
		(at 379.233684 -83.1088)
		(property "Reference" "R6303"
			(at 0 0 0)
			(layer "B.SilkS")
			(hide yes)
			(effects
				(font
					(size 1.27 1.27)
				)
				(justify mirror)
			)
		)
		(property "Value" ""
			(at 0 0 0)
			(layer "B.Fab")
			(effects
				(font
					(size 1.27 1.27)
				)
				(justify mirror)
			)
		)
		(duplicate_pad_numbers_are_jumpers no)
		(fp_line
			(start -0.7874 -0.4064)
			(end -0.7874 0.4064)
			(stroke
				(width 0.1524)
				(type default)
			)
			(layer "B.SilkS")
		)
		(fp_line
			(start -0.7874 0.4064)
			(end 0.7874 0.4064)
			(stroke
				(width 0.1524)
				(type default)
			)
			(layer "B.SilkS")
		)
		(fp_line
			(start 0.7874 -0.4064)
			(end -0.7874 -0.4064)
			(stroke
				(width 0.1524)
				(type default)
			)
			(layer "B.SilkS")
		)
		(fp_line
			(start 0.7874 0.4064)
			(end 0.7874 -0.4064)
			(stroke
				(width 0.1524)
				(type default)
			)
			(layer "B.SilkS")
		)
		(fp_line
			(start -0.67945 -0.3048)
			(end -0.67945 0.3048)
			(stroke
				(width 0.1)
				(type default)
			)
			(layer "B.Fab")
		)
		(fp_line
			(start -0.67945 0.3048)
			(end -0.120396 0.3048)
			(stroke
				(width 0.1)
				(type default)
			)
			(layer "B.Fab")
		)
		(fp_line
			(start -0.12065 -0.3048)
			(end -0.67945 -0.3048)
			(stroke
				(width 0.1)
				(type default)
			)
			(layer "B.Fab")
		)
		(fp_line
			(start -0.12065 -0.2794)
			(end -0.12065 -0.3048)
			(stroke
				(width 0.1)
				(type default)
			)
			(layer "B.Fab")
		)
		(fp_line
			(start -0.120396 0.2794)
			(end 0.12065 0.2794)
			(stroke
				(width 0.1)
				(type default)
			)
			(layer "B.Fab")
		)
		(fp_line
			(start -0.120396 0.3048)
			(end -0.120396 0.2794)
			(stroke
				(width 0.1)
				(type default)
			)
			(layer "B.Fab")
		)
		(fp_line
			(start 0.12065 -0.305054)
			(end 0.12065 -0.2794)
			(stroke
				(width 0.1)
				(type default)
			)
			(layer "B.Fab")
		)
		(fp_line
			(start 0.12065 -0.2794)
			(end -0.12065 -0.2794)
			(stroke
				(width 0.1)
				(type default)
			)
			(layer "B.Fab")
		)
		(fp_line
			(start 0.12065 0.2794)
			(end 0.12065 0.3048)
			(stroke
				(width 0.1)
				(type default)
			)
			(layer "B.Fab")
		)
		(fp_line
			(start 0.12065 0.3048)
			(end 0.67945 0.3048)
			(stroke
				(width 0.1)
				(type default)
			)
			(layer "B.Fab")
		)
		(fp_line
			(start 0.67945 -0.305054)
			(end 0.12065 -0.305054)
			(stroke
				(width 0.1)
				(type default)
			)
			(layer "B.Fab")
		)
		(fp_line
			(start 0.67945 0.3048)
			(end 0.67945 -0.305054)
			(stroke
				(width 0.1)
				(type default)
			)
			(layer "B.Fab")
		)
		(pad "1" smd circle
			(at 0.40005 0 180)
			(size 0 0)
			(layers "B.Cu" "B.Mask" "B.Paste")
			(net "SMB_BIC_I2C6_MUX_THERMAL_R1_SCL")
		)
		(pad "2" smd circle
			(at -0.40005 0 180)
			(size 0 0)
			(layers "B.Cu" "B.Mask" "B.Paste")
			(net "SMB_BIC_I2C6_MUX_THERMAL_R_SCL")
		)
	)
	(footprint ""
		(layer "B.Cu")
		(at 102.928674 -284.796738 -90)
		(property "Reference" "PC62"
			(at 0 0 90)
			(layer "B.SilkS")
			(hide yes)
			(effects
				(font
					(size 1.27 1.27)
				)
				(justify mirror)
			)
		)
		(property "Value" ""
			(at 0 0 90)
			(layer "B.Fab")
			(effects
				(font
					(size 1.27 1.27)
				)
				(justify mirror)
			)
		)
		(duplicate_pad_numbers_are_jumpers no)
		(fp_line
			(start -1.524 0.762)
			(end 1.524 0.762)
			(stroke
				(width 0.1524)
				(type default)
			)
			(layer "B.SilkS")
		)
		(fp_line
			(start 1.524 0.762)
			(end 1.524 -0.762)
			(stroke
				(width 0.1524)
				(type default)
			)
			(layer "B.SilkS")
		)
		(fp_line
			(start -1.524 -0.762)
			(end -1.524 0.762)
			(stroke
				(width 0.1524)
				(type default)
			)
			(layer "B.SilkS")
		)
		(fp_line
			(start 1.524 -0.762)
			(end -1.524 -0.762)
			(stroke
				(width 0.1524)
				(type default)
			)
			(layer "B.SilkS")
		)
		(fp_line
			(start -1.1049 0.724916)
			(end -1.1049 -0.724916)
			(stroke
				(width 0.1)
				(type default)
			)
			(layer "B.Fab")
		)
		(fp_line
			(start 1.1049 0.724916)
			(end -1.1049 0.724916)
			(stroke
				(width 0.1)
				(type default)
			)
			(layer "B.Fab")
		)
		(fp_line
			(start -1.1049 -0.724916)
			(end 1.1049 -0.724916)
			(stroke
				(width 0.1)
				(type default)
			)
			(layer "B.Fab")
		)
		(fp_line
			(start 1.1049 -0.724916)
			(end 1.1049 0.724916)
			(stroke
				(width 0.1)
				(type default)
			)
			(layer "B.Fab")
		)
		(pad "1" smd rect
			(at 0.889 0 270)
			(size 1.016 1.27)
			(layers "B.Cu" "B.Mask" "B.Paste")
			(net "SW_P12V_P0V8_PEX0_FLT")
		)
		(pad "2" smd rect
			(at -0.889 0 270)
			(size 1.016 1.27)
			(layers "B.Cu" "B.Mask" "B.Paste")
			(net "GND")
		)
	)
	(footprint ""
		(layer "B.Cu")
		(at 213.106 -201.549 90)
		(property "Reference" "R6309"
			(at 0 0 90)
			(layer "B.SilkS")
			(hide yes)
			(effects
				(font
					(size 1.27 1.27)
				)
				(justify mirror)
			)
		)
		(property "Value" ""
			(at 0 0 90)
			(layer "B.Fab")
			(effects
				(font
					(size 1.27 1.27)
				)
				(justify mirror)
			)
		)
		(duplicate_pad_numbers_are_jumpers no)
		(fp_line
			(start 0.7874 -0.4064)
			(end -0.7874 -0.4064)
			(stroke
				(width 0.1524)
				(type default)
			)
			(layer "B.SilkS")
		)
		(fp_line
			(start -0.7874 -0.4064)
			(end -0.7874 0.4064)
			(stroke
				(width 0.1524)
				(type default)
			)
			(layer "B.SilkS")
		)
		(fp_line
			(start 0.7874 0.4064)
			(end 0.7874 -0.4064)
			(stroke
				(width 0.1524)
				(type default)
			)
			(layer "B.SilkS")
		)
		(fp_line
			(start -0.7874 0.4064)
			(end 0.7874 0.4064)
			(stroke
				(width 0.1524)
				(type default)
			)
			(layer "B.SilkS")
		)
		(fp_line
			(start 0.67945 -0.305054)
			(end 0.12065 -0.305054)
			(stroke
				(width 0.1)
				(type default)
			)
			(layer "B.Fab")
		)
		(fp_line
			(start 0.12065 -0.305054)
			(end 0.12065 -0.2794)
			(stroke
				(width 0.1)
				(type default)
			)
			(layer "B.Fab")
		)
		(fp_line
			(start -0.12065 -0.3048)
			(end -0.67945 -0.3048)
			(stroke
				(width 0.1)
				(type default)
			)
			(layer "B.Fab")
		)
		(fp_line
			(start -0.67945 -0.3048)
			(end -0.67945 0.3048)
			(stroke
				(width 0.1)
				(type default)
			)
			(layer "B.Fab")
		)
		(fp_line
			(start 0.12065 -0.2794)
			(end -0.12065 -0.2794)
			(stroke
				(width 0.1)
				(type default)
			)
			(layer "B.Fab")
		)
		(fp_line
			(start -0.12065 -0.2794)
			(end -0.12065 -0.3048)
			(stroke
				(width 0.1)
				(type default)
			)
			(layer "B.Fab")
		)
		(fp_line
			(start 0.12065 0.2794)
			(end 0.12065 0.3048)
			(stroke
				(width 0.1)
				(type default)
			)
			(layer "B.Fab")
		)
		(fp_line
			(start -0.120396 0.2794)
			(end 0.12065 0.2794)
			(stroke
				(width 0.1)
				(type default)
			)
			(layer "B.Fab")
		)
		(fp_line
			(start 0.67945 0.3048)
			(end 0.67945 -0.305054)
			(stroke
				(width 0.1)
				(type default)
			)
			(layer "B.Fab")
		)
		(fp_line
			(start 0.12065 0.3048)
			(end 0.67945 0.3048)
			(stroke
				(width 0.1)
				(type default)
			)
			(layer "B.Fab")
		)
		(fp_line
			(start -0.120396 0.3048)
			(end -0.120396 0.2794)
			(stroke
				(width 0.1)
				(type default)
			)
			(layer "B.Fab")
		)
		(fp_line
			(start -0.67945 0.3048)
			(end -0.120396 0.3048)
			(stroke
				(width 0.1)
				(type default)
			)
			(layer "B.Fab")
		)
		(pad "1" smd circle
			(at 0.40005 0 270)
			(size 0 0)
			(layers "B.Cu" "B.Mask" "B.Paste")
			(net "SMB_NIC5_LS_SCL")
		)
		(pad "2" smd circle
			(at -0.40005 0 270)
			(size 0 0)
			(layers "B.Cu" "B.Mask" "B.Paste")
			(net "SMB_NIC5_LS_R_SCL")
		)
	)
	(footprint ""
		(layer "B.Cu")
		(at 289.94989 -301.599854 -90)
		(property "Reference" "C1737"
			(at 0 0 90)
			(layer "B.SilkS")
			(hide yes)
			(effects
				(font
					(size 1.27 1.27)
				)
				(justify mirror)
			)
		)
		(property "Value" ""
			(at 0 0 90)
			(layer "B.Fab")
			(effects
				(font
					(size 1.27 1.27)
				)
				(justify mirror)
			)
		)
		(duplicate_pad_numbers_are_jumpers no)
		(fp_line
			(start -0.299974 0.150114)
			(end 0.299974 0.150114)
			(stroke
				(width 0.1)
				(type default)
			)
			(layer "B.Fab")
		)
		(fp_line
			(start 0.299974 0.150114)
			(end 0.299974 -0.150114)
			(stroke
				(width 0.1)
				(type default)
			)
			(layer "B.Fab")
		)
		(fp_line
			(start -0.299974 -0.150114)
			(end -0.299974 0.150114)
			(stroke
				(width 0.1)
				(type default)
			)
			(layer "B.Fab")
		)
		(fp_line
			(start 0.299974 -0.150114)
			(end -0.299974 -0.150114)
			(stroke
				(width 0.1)
				(type default)
			)
			(layer "B.Fab")
		)
		(pad "1" smd rect
			(at 0.2667 0 90)
			(size 0.3048 0.381)
			(layers "B.Cu" "B.Mask" "B.Paste")
			(net "P0V8_SERDES_VDDA_PEX2")
		)
		(pad "2" smd rect
			(at -0.2667 0 90)
			(size 0.3048 0.381)
			(layers "B.Cu" "B.Mask" "B.Paste")
			(net "GND")
		)
	)
	(footprint ""
		(layer "B.Cu")
		(at 350.139 -233.553 90)
		(property "Reference" "R3597"
			(at 0 0 90)
			(layer "B.SilkS")
			(hide yes)
			(effects
				(font
					(size 1.27 1.27)
				)
				(justify mirror)
			)
		)
		(property "Value" ""
			(at 0 0 90)
			(layer "B.Fab")
			(effects
				(font
					(size 1.27 1.27)
				)
				(justify mirror)
			)
		)
		(duplicate_pad_numbers_are_jumpers no)
		(fp_line
			(start 0.7874 -0.4064)
			(end -0.7874 -0.4064)
			(stroke
				(width 0.1524)
				(type default)
			)
			(layer "B.SilkS")
		)
		(fp_line
			(start -0.7874 -0.4064)
			(end -0.7874 0.4064)
			(stroke
				(width 0.1524)
				(type default)
			)
			(layer "B.SilkS")
		)
		(fp_line
			(start 0.7874 0.4064)
			(end 0.7874 -0.4064)
			(stroke
				(width 0.1524)
				(type default)
			)
			(layer "B.SilkS")
		)
		(fp_line
			(start -0.7874 0.4064)
			(end 0.7874 0.4064)
			(stroke
				(width 0.1524)
				(type default)
			)
			(layer "B.SilkS")
		)
		(fp_line
			(start 0.67945 -0.305054)
			(end 0.12065 -0.305054)
			(stroke
				(width 0.1)
				(type default)
			)
			(layer "B.Fab")
		)
		(fp_line
			(start 0.12065 -0.305054)
			(end 0.12065 -0.2794)
			(stroke
				(width 0.1)
				(type default)
			)
			(layer "B.Fab")
		)
		(fp_line
			(start -0.12065 -0.3048)
			(end -0.67945 -0.3048)
			(stroke
				(width 0.1)
				(type default)
			)
			(layer "B.Fab")
		)
		(fp_line
			(start -0.67945 -0.3048)
			(end -0.67945 0.3048)
			(stroke
				(width 0.1)
				(type default)
			)
			(layer "B.Fab")
		)
		(fp_line
			(start 0.12065 -0.2794)
			(end -0.12065 -0.2794)
			(stroke
				(width 0.1)
				(type default)
			)
			(layer "B.Fab")
		)
		(fp_line
			(start -0.12065 -0.2794)
			(end -0.12065 -0.3048)
			(stroke
				(width 0.1)
				(type default)
			)
			(layer "B.Fab")
		)
		(fp_line
			(start 0.12065 0.2794)
			(end 0.12065 0.3048)
			(stroke
				(width 0.1)
				(type default)
			)
			(layer "B.Fab")
		)
		(fp_line
			(start -0.120396 0.2794)
			(end 0.12065 0.2794)
			(stroke
				(width 0.1)
				(type default)
			)
			(layer "B.Fab")
		)
		(fp_line
			(start 0.67945 0.3048)
			(end 0.67945 -0.305054)
			(stroke
				(width 0.1)
				(type default)
			)
			(layer "B.Fab")
		)
		(fp_line
			(start 0.12065 0.3048)
			(end 0.67945 0.3048)
			(stroke
				(width 0.1)
				(type default)
			)
			(layer "B.Fab")
		)
		(fp_line
			(start -0.120396 0.3048)
			(end -0.120396 0.2794)
			(stroke
				(width 0.1)
				(type default)
			)
			(layer "B.Fab")
		)
		(fp_line
			(start -0.67945 0.3048)
			(end -0.120396 0.3048)
			(stroke
				(width 0.1)
				(type default)
			)
			(layer "B.Fab")
		)
		(pad "1" smd circle
			(at 0.40005 0 270)
			(size 0 0)
			(layers "B.Cu" "B.Mask" "B.Paste")
			(net "SSD7_CLK_EN_R_N")
		)
		(pad "2" smd circle
			(at -0.40005 0 270)
			(size 0 0)
			(layers "B.Cu" "B.Mask" "B.Paste")
			(net "SSD7_CLK_EN_N")
		)
	)
)
